%#################################################################
Title:        Cref Error Report
Design:       s9s_mb_2u
Date:         Sep 23 11:20:32 2022
%#################################################################



Warnings in Page : @s9s_mb_2u_lib.s9s_mb_2u(sch_1):Page152
Signal USB2_HUB_BUF_SWB_R_DN at (A 4) has too little display space.
Signal USB2_HUB_BUF_SWB_R_DP at (A 4) has too little display space.

Warnings in Page : @s9s_mb_2u_lib.s9s_mb_2u(sch_1):Page167
Signal FM_P2E_BUF2_VODB_DB at (B 3) has too little display space.
Signal FM_P2E_BUF2_VODA_DB at (B 3) has too little display space.

Warnings in Page : @s9s_mb_2u_lib.s9s_mb_2u(sch_1):Page185
Signal       P3V_BAT_R at (B 2) has too little display space.

Warnings in Page : @s9s_mb_2u_lib.s9s_mb_2u(sch_1):Page196
Signal USB2_HUB_2_BUF_EXT_R_DP at (A 4) has too little display space.
Signal USB2_HUB_2_BUF_EXT_R_DN at (A 4) has too little display space.

Warnings in Page : @s9s_mb_2u_lib.s9s_mb_2u(sch_1):Page268
Signal PVCCIN_CPU0_PWM3 at (B 4) has too little display space.

Warnings in Page : @s9s_mb_2u_lib.s9s_mb_2u(sch_1):Page269
Signal PVCCIN_CPU0_PWM6 at (A 4) has too little display space.

Warnings in Page : @s9s_mb_2u_lib.s9s_mb_2u(sch_1):Page270
Signal PVCCIN_CPU0_PWM8 at (A 4) has too little display space.

Warnings in Page : @s9s_mb_2u_lib.s9s_mb_2u(sch_1):Page286
Signal PVCCIN_CPU1_PWM3 at (B 4) has too little display space.
Signal PVCCIN_CPU1_PWM4 at (A 4) has too little display space.

Warnings in Page : @s9s_mb_2u_lib.s9s_mb_2u(sch_1):Page287
Signal PVCCIN_CPU1_PWM5 at (B 4) has too little display space.
Signal PVCCIN_CPU1_PWM6 at (A 4) has too little display space.

Warnings in Page : @s9s_mb_2u_lib.s9s_mb_2u(sch_1):Page288
Signal PVCCIN_CPU1_PWM7 at (B 4) has too little display space.
Signal PVCCIN_CPU1_PWM8 at (A 4) has too little display space.
